(kicad_pcb
	(version 20260206)
	(generator "pcbnew")
	(generator_version "10.0")
	(general
		(thickness 1.6)
		(legacy_teardrops no)
	)
	(paper "A4")
	(title_block
		(title "03242023_DA0F0TMBIJ0_F0T_Motherboard_J_brd_V01_OCP.brd")
		(comment 1 "Grand Teton / footprints 1333-1334 of 6105")
	)
	(layers
		(0 "F.Cu" signal "TOP")
		(4 "In1.Cu" signal "GND")
		(6 "In2.Cu" signal "IN1")
		(8 "In3.Cu" signal "GND1")
		(10 "In4.Cu" signal "IN2")
		(12 "In5.Cu" signal "GND2")
		(14 "In6.Cu" signal "IN3")
		(16 "In7.Cu" signal "GND3")
		(18 "In8.Cu" signal "VCC")
		(20 "In9.Cu" signal "VCC1")
		(22 "In10.Cu" signal "GND4")
		(24 "In11.Cu" signal "IN4")
		(26 "In12.Cu" signal "GND5")
		(28 "In13.Cu" signal "IN5")
		(30 "In14.Cu" signal "GND6")
		(32 "In15.Cu" signal "IN6")
		(34 "In16.Cu" signal "GND7")
		(2 "B.Cu" signal "BOTTOM")
		(9 "F.Adhes" user "F.Adhesive")
		(11 "B.Adhes" user "B.Adhesive")
		(13 "F.Paste" user "Package Geometry/Pastemask Top")
		(15 "B.Paste" user "Package Geometry/Pastemask Bottom")
		(5 "F.SilkS" user "Ref Des/Silkscreen Top")
		(7 "B.SilkS" user "Ref Des/Silkscreen Bottom")
		(1 "F.Mask" user "Board Geometry/Soldermask Top")
		(3 "B.Mask" user "Board Geometry/Soldermask Bottom")
		(17 "Dwgs.User" user "User.Drawings")
		(19 "Cmts.User" user "User.Comments")
		(21 "Eco1.User" user "User.Eco1")
		(23 "Eco2.User" user "User.Eco2")
		(25 "Edge.Cuts" user "Board Geometry/Outline")
		(27 "Margin" user)
		(31 "F.CrtYd" user "Package Geometry/Place Bound Top")
		(29 "B.CrtYd" user "Package Geometry/Place Bound Bottom")
		(35 "F.Fab" user "Ref Des/Assembly Top")
		(33 "B.Fab" user "Ref Des/Assembly Bottom")
	)
	(footprint ""
		(layer "F.Cu")
		(at 367.44783 -247.715024 90)
		(property "Reference" "C399"
			(at 0 0 90)
			(layer "F.SilkS")
			(hide yes)
			(effects
				(font
					(size 1.27 1.27)
				)
			)
		)
		(property "Value" ""
			(at 0 0 90)
			(layer "F.Fab")
			(effects
				(font
					(size 1.27 1.27)
				)
			)
		)
		(duplicate_pad_numbers_are_jumpers no)
		(fp_line
			(start 0.7874 -0.4064)
			(end 0.7874 0.4064)
			(stroke
				(width 0.1524)
				(type default)
			)
			(layer "F.SilkS")
		)
		(fp_line
			(start -0.7874 -0.4064)
			(end 0.7874 -0.4064)
			(stroke
				(width 0.1524)
				(type default)
			)
			(layer "F.SilkS")
		)
		(fp_line
			(start 0.7874 0.4064)
			(end -0.7874 0.4064)
			(stroke
				(width 0.1524)
				(type default)
			)
			(layer "F.SilkS")
		)
		(fp_line
			(start -0.7874 0.4064)
			(end -0.7874 -0.4064)
			(stroke
				(width 0.1524)
				(type default)
			)
			(layer "F.SilkS")
		)
		(fp_line
			(start -0.12065 -0.305054)
			(end -0.12065 -0.2794)
			(stroke
				(width 0.1)
				(type default)
			)
			(layer "F.Fab")
		)
		(fp_line
			(start -0.67945 -0.305054)
			(end -0.12065 -0.305054)
			(stroke
				(width 0.1)
				(type default)
			)
			(layer "F.Fab")
		)
		(fp_line
			(start 0.67945 -0.3048)
			(end 0.67945 0.3048)
			(stroke
				(width 0.1)
				(type default)
			)
			(layer "F.Fab")
		)
		(fp_line
			(start 0.12065 -0.3048)
			(end 0.67945 -0.3048)
			(stroke
				(width 0.1)
				(type default)
			)
			(layer "F.Fab")
		)
		(fp_line
			(start 0.12065 -0.2794)
			(end 0.12065 -0.3048)
			(stroke
				(width 0.1)
				(type default)
			)
			(layer "F.Fab")
		)
		(fp_line
			(start -0.12065 -0.2794)
			(end 0.12065 -0.2794)
			(stroke
				(width 0.1)
				(type default)
			)
			(layer "F.Fab")
		)
		(fp_line
			(start 0.120396 0.2794)
			(end -0.12065 0.2794)
			(stroke
				(width 0.1)
				(type default)
			)
			(layer "F.Fab")
		)
		(fp_line
			(start -0.12065 0.2794)
			(end -0.12065 0.3048)
			(stroke
				(width 0.1)
				(type default)
			)
			(layer "F.Fab")
		)
		(fp_line
			(start 0.67945 0.3048)
			(end 0.120396 0.3048)
			(stroke
				(width 0.1)
				(type default)
			)
			(layer "F.Fab")
		)
		(fp_line
			(start 0.120396 0.3048)
			(end 0.120396 0.2794)
			(stroke
				(width 0.1)
				(type default)
			)
			(layer "F.Fab")
		)
		(fp_line
			(start -0.12065 0.3048)
			(end -0.67945 0.3048)
			(stroke
				(width 0.1)
				(type default)
			)
			(layer "F.Fab")
		)
		(fp_line
			(start -0.67945 0.3048)
			(end -0.67945 -0.305054)
			(stroke
				(width 0.1)
				(type default)
			)
			(layer "F.Fab")
		)
		(pad "1" smd circle
			(at -0.40005 0 90)
			(size 0 0)
			(layers "F.Cu" "F.Mask" "F.Paste")
			(net "PVCCD_HV_CPU0")
		)
		(pad "2" smd circle
			(at 0.40005 0 90)
			(size 0 0)
			(layers "F.Cu" "F.Mask" "F.Paste")
			(net "GND")
		)
	)
	(footprint ""
		(layer "F.Cu")
		(at 68.212462 -37.389562 180)
		(property "Reference" "R3559"
			(at 0 0 180)
			(layer "F.SilkS")
			(hide yes)
			(effects
				(font
					(size 1.27 1.27)
				)
			)
		)
		(property "Value" ""
			(at 0 0 180)
			(layer "F.Fab")
			(effects
				(font
					(size 1.27 1.27)
				)
			)
		)
		(duplicate_pad_numbers_are_jumpers no)
		(fp_line
			(start 0.7874 0.4064)
			(end -0.7874 0.4064)
			(stroke
				(width 0.1524)
				(type default)
			)
			(layer "F.SilkS")
		)
		(fp_line
			(start 0.7874 -0.4064)
			(end 0.7874 0.4064)
			(stroke
				(width 0.1524)
				(type default)
			)
			(layer "F.SilkS")
		)
		(fp_line
			(start -0.7874 0.4064)
			(end -0.7874 -0.4064)
			(stroke
				(width 0.1524)
				(type default)
			)
			(layer "F.SilkS")
		)
		(fp_line
			(start -0.7874 -0.4064)
			(end 0.7874 -0.4064)
			(stroke
				(width 0.1524)
				(type default)
			)
			(layer "F.SilkS")
		)
		(fp_line
			(start 0.67945 0.3048)
			(end 0.120396 0.3048)
			(stroke
				(width 0.1)
				(type default)
			)
			(layer "F.Fab")
		)
		(fp_line
			(start 0.67945 -0.3048)
			(end 0.67945 0.3048)
			(stroke
				(width 0.1)
				(type default)
			)
			(layer "F.Fab")
		)
		(fp_line
			(start 0.12065 -0.2794)
			(end 0.12065 -0.3048)
			(stroke
				(width 0.1)
				(type default)
			)
			(layer "F.Fab")
		)
		(fp_line
			(start 0.12065 -0.3048)
			(end 0.67945 -0.3048)
			(stroke
				(width 0.1)
				(type default)
			)
			(layer "F.Fab")
		)
		(fp_line
			(start 0.120396 0.3048)
			(end 0.120396 0.2794)
			(stroke
				(width 0.1)
				(type default)
			)
			(layer "F.Fab")
		)
		(fp_line
			(start 0.120396 0.2794)
			(end -0.12065 0.2794)
			(stroke
				(width 0.1)
				(type default)
			)
			(layer "F.Fab")
		)
		(fp_line
			(start -0.12065 0.3048)
			(end -0.67945 0.3048)
			(stroke
				(width 0.1)
				(type default)
			)
			(layer "F.Fab")
		)
		(fp_line
			(start -0.12065 0.2794)
			(end -0.12065 0.3048)
			(stroke
				(width 0.1)
				(type default)
			)
			(layer "F.Fab")
		)
		(fp_line
			(start -0.12065 -0.2794)
			(end 0.12065 -0.2794)
			(stroke
				(width 0.1)
				(type default)
			)
			(layer "F.Fab")
		)
		(fp_line
			(start -0.12065 -0.305054)
			(end -0.12065 -0.2794)
			(stroke
				(width 0.1)
				(type default)
			)
			(layer "F.Fab")
		)
		(fp_line
			(start -0.67945 0.3048)
			(end -0.67945 -0.305054)
			(stroke
				(width 0.1)
				(type default)
			)
			(layer "F.Fab")
		)
		(fp_line
			(start -0.67945 -0.305054)
			(end -0.12065 -0.305054)
			(stroke
				(width 0.1)
				(type default)
			)
			(layer "F.Fab")
		)
		(pad "1" smd circle
			(at -0.40005 0 180)
			(size 0 0)
			(layers "F.Cu" "F.Mask" "F.Paste")
			(net "OCP_V3_2_P3V3_ADC_ALERT_R")
		)
		(pad "2" smd circle
			(at 0.40005 0 180)
			(size 0 0)
			(layers "F.Cu" "F.Mask" "F.Paste")
			(net "OCP_V3_2_P3V3_ADC_ALERT")
		)
	)
)
